#ISCELL
  mstr_symbols intel_corp_bpage *
  *
#CELL
  mstr_discrete res *
  page190_i116
#CELL
  mstr_discrete res *
  page190_i117
#ISCELL
  mstr_standard offpage *
  page190_i118
#ISCELL
  mstr_standard offpage *
  page190_i119
#ISCELL
  mstr_standard offpage *
  page190_i120
#ISCELL
  mstr_standard offpage *
  page190_i121
#ISCELL
  mstr_standard offpage *
  page190_i122
#ISCELL
  mstr_standard offpage *
  page190_i134
#ISCELL
  mstr_standard offpage *
  page190_i139
#ISCELL
  mstr_standard offpage *
  page190_i146
#ISCELL
  mstr_standard offpage *
  page190_i157
#ISCELL
  mstr_standard offpage *
  page190_i159
#ISCELL
  mstr_standard offpage *
  page190_i161
#ISCELL
  mstr_standard offpage *
  page190_i162
#ISCELL
  mstr_standard offpage *
  page190_i165
#ISCELL
  mstr_standard offpage *
  page190_i167
#ISCELL
  mstr_standard offpage *
  page190_i168
#ISCELL
  mstr_standard offpage *
  page190_i171
#CELL
  mstr_memory lcmxo2_a *
  page190_i179
#ISCELL
  mstr_standard offpage *
  page190_i220
#ISCELL
  mstr_standard offpage *
  page190_i221
#ISCELL
  mstr_standard offpage *
  page190_i224
#ISCELL
  mstr_standard offpage *
  page190_i225
#ISCELL
  mstr_standard offpage *
  page190_i226
#ISCELL
  mstr_standard offpage *
  page190_i227
#ISCELL
  mstr_standard offpage *
  page190_i231
#ISCELL
  mstr_standard offpage *
  page190_i234
#ISCELL
  mstr_standard offpage *
  page190_i235
#ISCELL
  mstr_standard offpage *
  page190_i236
#ISCELL
  mstr_standard offpage *
  page190_i237
#ISCELL
  mstr_standard offpage *
  page190_i239
#ISCELL
  mstr_standard offpage *
  page190_i240
#ISCELL
  mstr_standard offpage *
  page190_i241
#ISCELL
  mstr_standard offpage *
  page190_i243
#ISCELL
  mstr_standard offpage *
  page190_i244
#ISCELL
  mstr_standard offpage *
  page190_i246
#ISCELL
  mstr_standard offpage *
  page190_i248
#ISCELL
  mstr_standard offpage *
  page190_i252
#ISCELL
  mstr_standard offpage *
  page190_i255
#ISCELL
  mstr_standard offpage *
  page190_i260
#ISCELL
  mstr_standard offpage *
  page190_i261
#ISCELL
  mstr_standard offpage *
  page190_i263
#ISCELL
  mstr_standard offpage *
  page190_i267
#ISCELL
  mstr_standard offpage *
  page190_i268
#ISCELL
  mstr_standard offpage *
  page190_i269
#ISCELL
  mstr_standard offpage *
  page190_i270
#ISCELL
  mstr_standard offpage *
  page190_i271
#ISCELL
  mstr_standard offpage *
  page190_i272
#ISCELL
  mstr_standard offpage *
  page190_i273
#ISCELL
  mstr_standard offpage *
  page190_i274
#ISCELL
  mstr_standard offpage *
  page190_i275
#ISCELL
  mstr_standard offpage *
  page190_i276
#ISCELL
  mstr_standard offpage *
  page190_i277
#ISCELL
  mstr_standard offpage *
  page190_i279
#ISCELL
  mstr_standard offpage *
  page190_i280
#ISCELL
  mstr_standard offpage *
  page190_i284
#ISCELL
  mstr_standard offpage *
  page190_i285
#ISCELL
  mstr_standard offpage *
  page190_i298
#ISCELL
  mstr_standard offpage *
  page190_i299
#ISCELL
  mstr_standard offpage *
  page190_i301
#ISCELL
  mstr_standard offpage *
  page190_i302
#ISCELL
  mstr_standard offpage *
  page190_i303
#ISCELL
  mstr_standard offpage *
  page190_i304
#ISCELL
  mstr_standard offpage *
  page190_i305
#ISCELL
  mstr_standard offpage *
  page190_i306
#ISCELL
  mstr_standard offpage *
  page190_i307
#ISCELL
  mstr_standard offpage *
  page190_i308
#ISCELL
  mstr_standard offpage *
  page190_i309
#ISCELL
  mstr_standard offpage *
  page190_i312
#ISCELL
  mstr_standard offpage *
  page190_i313
#ISCELL
  mstr_standard offpage *
  page190_i314
#ISCELL
  mstr_standard offpage *
  page190_i317
#ISCELL
  mstr_standard offpage *
  page190_i318
#ISCELL
  mstr_standard offpage *
  page190_i319
#ISCELL
  mstr_standard offpage *
  page190_i320
#ISCELL
  mstr_standard offpage *
  page190_i321
#ISCELL
  mstr_standard offpage *
  page190_i322
#ISCELL
  mstr_standard offpage *
  page190_i323
#ISCELL
  mstr_standard offpage *
  page190_i324
#ISCELL
  mstr_standard offpage *
  page190_i325
#ISCELL
  mstr_standard offpage *
  page190_i326
#ISCELL
  mstr_standard offpage *
  page190_i327
#ISCELL
  mstr_standard offpage *
  page190_i328
#ISCELL
  mstr_standard offpage *
  page190_i329
#ISCELL
  mstr_standard offpage *
  page190_i330
#ISCELL
  mstr_standard offpage *
  page190_i331
#ISCELL
  mstr_standard offpage *
  page190_i332
#ISCELL
  mstr_standard offpage *
  page190_i333
#ISCELL
  mstr_standard offpage *
  page190_i334
#ISCELL
  mstr_standard offpage *
  page190_i335
#ISCELL
  mstr_standard offpage *
  page190_i336
#ISCELL
  mstr_standard offpage *
  page190_i337
#CELL
  mstr_discrete res *
  page190_i338
#ISCELL
  mstr_standard offpage *
  page190_i339
#ISCELL
  mstr_standard offpage *
  page190_i340
#ISCELL
  mstr_standard offpage *
  page190_i341
#ISCELL
  mstr_standard offpage *
  page190_i342
#ISCELL
  mstr_standard offpage *
  page190_i343
#ISCELL
  mstr_standard offpage *
  page190_i344
#ISCELL
  mstr_standard offpage *
  page190_i345
#ISCELL
  mstr_standard offpage *
  page190_i346
